(kicad_pcb
	(version 20260206)
	(generator "pcbnew")
	(generator_version "10.0")
	(general
		(thickness 1.6)
		(legacy_teardrops no)
	)
	(paper "A4")
	(title_block
		(title "baseboard — 13948-1b.1110WZS1818.brd")
		(comment 1 "Honey Badger (Wiwynn) / footprints 797-803 of 2523")
	)
	(layers
		(0 "F.Cu" signal "TOP")
		(4 "In1.Cu" signal "L2GND")
		(6 "In2.Cu" signal "L3")
		(8 "In3.Cu" signal "L4VCC")
		(10 "In4.Cu" signal "L5VCC")
		(12 "In5.Cu" signal "L6")
		(14 "In6.Cu" signal "L7GND")
		(2 "B.Cu" signal "BOTTOM")
		(9 "F.Adhes" user "F.Adhesive")
		(11 "B.Adhes" user "B.Adhesive")
		(13 "F.Paste" user "Package Geometry/Pastemask Top")
		(15 "B.Paste" user "Package Geometry/Pastemask Bottom")
		(5 "F.SilkS" user "Ref Des/Silkscreen Top")
		(7 "B.SilkS" user "Ref Des/Silkscreen Bottom")
		(1 "F.Mask" user "Board Geometry/Soldermask Top")
		(3 "B.Mask" user "Board Geometry/Soldermask Bottom")
		(17 "Dwgs.User" user "User.Drawings")
		(19 "Cmts.User" user "User.Comments")
		(21 "Eco1.User" user "User.Eco1")
		(23 "Eco2.User" user "User.Eco2")
		(25 "Edge.Cuts" user "Board Geometry/Outline")
		(27 "Margin" user)
		(31 "F.CrtYd" user "Package Geometry/Place Bound Top")
		(29 "B.CrtYd" user "Package Geometry/Place Bound Bottom")
		(35 "F.Fab" user "Ref Des/Assembly Top")
		(33 "B.Fab" user "Ref Des/Assembly Bottom")
	)
	(footprint ""
		(layer "F.Cu")
		(at 167.503348 -122.545856)
		(property "Reference" "PR158"
			(at 0 0 0)
			(layer "F.SilkS")
			(hide yes)
			(effects
				(font
					(size 1.27 1.27)
				)
			)
		)
		(property "Value" "100KR2F-L1-GP"
			(at 0.064008 -3.993896 0)
			(unlocked yes)
			(layer "F.Fab")
			(hide yes)
			(effects
				(font
					(size 1.016 1.016)
					(thickness 0.1524)
				)
			)
		)
		(property "Device Type" "R402H16"
			(at 0.064008 -5.517896 0)
			(unlocked yes)
			(layer "F.Fab")
			(hide yes)
			(effects
				(font
					(size 1.016 1.016)
					(thickness 0.1524)
				)
			)
		)
		(duplicate_pad_numbers_are_jumpers no)
		(fp_line
			(start -0.508 -0.9398)
			(end -0.508 0.9398)
			(stroke
				(width 0.1524)
				(type default)
			)
			(layer "F.SilkS")
		)
		(fp_line
			(start 0.508 -0.9398)
			(end -0.508 -0.9398)
			(stroke
				(width 0.1524)
				(type default)
			)
			(layer "F.SilkS")
		)
		(fp_rect
			(start -0.508 0.9398)
			(end 0.508 -0.9398)
			(stroke
				(width 0)
				(type default)
			)
			(fill no)
			(layer "F.CrtYd")
		)
		(fp_rect
			(start -0.508 0.9398)
			(end 0.508 -0.9398)
			(stroke
				(width 0)
				(type default)
			)
			(fill no)
			(layer "F.Fab")
		)
		(pad "1" smd custom
			(at 0 -0.4445)
			(size 0.1397 0.1397)
			(layers "F.Cu" "F.Mask" "F.Paste")
			(net "P0V9_E_VREG")
			(options
				(clearance outline)
				(anchor circle)
			)
			(primitives
				(gr_poly
					(pts
						(arc
							(start -0.1778 -0.2794)
							(mid -0.249642 -0.249642)
							(end -0.2794 -0.1778)
						)
						(arc
							(start -0.2794 0.1778)
							(mid -0.249642 0.249642)
							(end -0.1778 0.2794)
						)
						(arc
							(start 0.1778 0.2794)
							(mid 0.249642 0.249642)
							(end 0.2794 0.1778)
						)
						(arc
							(start 0.2794 -0.1778)
							(mid 0.249642 -0.249642)
							(end 0.1778 -0.2794)
						)
					)
					(width 0)
					(fill yes)
				)
			)
		)
		(pad "2" smd custom
			(at 0 0.4445)
			(size 0.1397 0.1397)
			(layers "F.Cu" "F.Mask" "F.Paste")
			(net "P0V9_E_RF")
			(options
				(clearance outline)
				(anchor circle)
			)
			(primitives
				(gr_poly
					(pts
						(arc
							(start -0.1778 -0.2794)
							(mid -0.249642 -0.249642)
							(end -0.2794 -0.1778)
						)
						(arc
							(start -0.2794 0.1778)
							(mid -0.249642 0.249642)
							(end -0.1778 0.2794)
						)
						(arc
							(start 0.1778 0.2794)
							(mid 0.249642 0.249642)
							(end 0.2794 0.1778)
						)
						(arc
							(start 0.2794 -0.1778)
							(mid 0.249642 -0.249642)
							(end 0.1778 -0.2794)
						)
					)
					(width 0)
					(fill yes)
				)
			)
		)
	)
	(footprint ""
		(layer "F.Cu")
		(at 269.739872 -56.714136 -90)
		(property "Reference" "PR115"
			(at 0 0 270)
			(layer "F.SilkS")
			(hide yes)
			(effects
				(font
					(size 1.27 1.27)
				)
			)
		)
		(property "Value" "4K02R2F-GP"
			(at 0.064008 -3.993896 270)
			(unlocked yes)
			(layer "F.Fab")
			(hide yes)
			(effects
				(font
					(size 1.016 1.016)
					(thickness 0.1524)
				)
			)
		)
		(property "Device Type" "R402H16"
			(at 0.064008 -5.517896 270)
			(unlocked yes)
			(layer "F.Fab")
			(hide yes)
			(effects
				(font
					(size 1.016 1.016)
					(thickness 0.1524)
				)
			)
		)
		(duplicate_pad_numbers_are_jumpers no)
		(fp_line
			(start -0.508 -0.9398)
			(end -0.508 0.9398)
			(stroke
				(width 0.1524)
				(type default)
			)
			(layer "F.SilkS")
		)
		(fp_line
			(start 0.508 -0.9398)
			(end -0.508 -0.9398)
			(stroke
				(width 0.1524)
				(type default)
			)
			(layer "F.SilkS")
		)
		(fp_rect
			(start -0.508 0.9398)
			(end 0.508 -0.9398)
			(stroke
				(width 0)
				(type default)
			)
			(fill no)
			(layer "F.CrtYd")
		)
		(fp_rect
			(start -0.508 0.9398)
			(end 0.508 -0.9398)
			(stroke
				(width 0)
				(type default)
			)
			(fill no)
			(layer "F.Fab")
		)
		(pad "1" smd custom
			(at 0 -0.4445 270)
			(size 0.1397 0.1397)
			(layers "F.Cu" "F.Mask" "F.Paste")
			(net "P3V3_EN_B")
			(options
				(clearance outline)
				(anchor circle)
			)
			(primitives
				(gr_poly
					(pts
						(arc
							(start -0.1778 -0.2794)
							(mid -0.249642 -0.249642)
							(end -0.2794 -0.1778)
						)
						(arc
							(start -0.2794 0.1778)
							(mid -0.249642 0.249642)
							(end -0.1778 0.2794)
						)
						(arc
							(start 0.1778 0.2794)
							(mid 0.249642 0.249642)
							(end 0.2794 0.1778)
						)
						(arc
							(start 0.2794 -0.1778)
							(mid 0.249642 -0.249642)
							(end 0.1778 -0.2794)
						)
					)
					(width 0)
					(fill yes)
				)
			)
		)
		(pad "2" smd custom
			(at 0 0.4445 270)
			(size 0.1397 0.1397)
			(layers "F.Cu" "F.Mask" "F.Paste")
			(net "P3V3_STBY")
			(options
				(clearance outline)
				(anchor circle)
			)
			(primitives
				(gr_poly
					(pts
						(arc
							(start -0.1778 -0.2794)
							(mid -0.249642 -0.249642)
							(end -0.2794 -0.1778)
						)
						(arc
							(start -0.2794 0.1778)
							(mid -0.249642 0.249642)
							(end -0.1778 0.2794)
						)
						(arc
							(start 0.1778 0.2794)
							(mid 0.249642 0.249642)
							(end 0.2794 0.1778)
						)
						(arc
							(start 0.2794 -0.1778)
							(mid 0.249642 -0.249642)
							(end 0.1778 -0.2794)
						)
					)
					(width 0)
					(fill yes)
				)
			)
		)
	)
	(footprint ""
		(layer "F.Cu")
		(at 87.103966 -61.341 90)
		(property "Reference" "SC886"
			(at 0 0 90)
			(layer "F.SilkS")
			(hide yes)
			(effects
				(font
					(size 1.27 1.27)
				)
			)
		)
		(property "Value" "SC12P50V2JN-3GP"
			(at 1.1811 -2.7051 90)
			(unlocked yes)
			(layer "F.Fab")
			(hide yes)
			(effects
				(font
					(size 1.016 1.016)
					(thickness 0.1524)
				)
			)
		)
		(property "Device Type" "C402H24"
			(at 1.1811 -4.2291 90)
			(unlocked yes)
			(layer "F.Fab")
			(hide yes)
			(effects
				(font
					(size 1.016 1.016)
					(thickness 0.1524)
				)
			)
		)
		(duplicate_pad_numbers_are_jumpers no)
		(fp_rect
			(start -0.4318 0.9525)
			(end 0.4318 -0.9525)
			(stroke
				(width 0)
				(type default)
			)
			(fill no)
			(layer "F.CrtYd")
		)
		(fp_rect
			(start -0.4318 0.9525)
			(end 0.4318 -0.9525)
			(stroke
				(width 0)
				(type default)
			)
			(fill no)
			(layer "F.Fab")
		)
		(pad "1" smd custom
			(at 0 -0.4445 90)
			(size 0.1524 0.1524)
			(layers "F.Cu" "F.Mask" "F.Paste")
			(net "REF_CLK")
			(options
				(clearance outline)
				(anchor circle)
			)
			(primitives
				(gr_poly
					(pts
						(arc
							(start 0.3048 -0.2032)
							(mid 0.275042 -0.275042)
							(end 0.2032 -0.3048)
						)
						(arc
							(start -0.2032 -0.3048)
							(mid -0.275042 -0.275042)
							(end -0.3048 -0.2032)
						)
						(arc
							(start -0.3048 0.2032)
							(mid -0.275042 0.275042)
							(end -0.2032 0.3048)
						)
						(arc
							(start 0.2032 0.3048)
							(mid 0.275042 0.275042)
							(end 0.3048 0.2032)
						)
					)
					(width 0)
					(fill yes)
				)
			)
		)
		(pad "2" smd custom
			(at 0 0.4445 90)
			(size 0.1524 0.1524)
			(layers "F.Cu" "F.Mask" "F.Paste")
			(net "GND")
			(options
				(clearance outline)
				(anchor circle)
			)
			(primitives
				(gr_poly
					(pts
						(arc
							(start 0.3048 -0.2032)
							(mid 0.275042 -0.275042)
							(end 0.2032 -0.3048)
						)
						(arc
							(start -0.2032 -0.3048)
							(mid -0.275042 -0.275042)
							(end -0.3048 -0.2032)
						)
						(arc
							(start -0.3048 0.2032)
							(mid -0.275042 0.275042)
							(end -0.2032 0.3048)
						)
						(arc
							(start 0.2032 0.3048)
							(mid 0.275042 0.275042)
							(end 0.3048 0.2032)
						)
					)
					(width 0)
					(fill yes)
				)
			)
		)
	)
	(footprint ""
		(layer "F.Cu")
		(at 270.764 -187.325 90)
		(property "Reference" "C322"
			(at 0 0 90)
			(layer "F.SilkS")
			(hide yes)
			(effects
				(font
					(size 1.27 1.27)
				)
			)
		)
		(property "Value" "SCD1U16V2KX-3GP"
			(at 1.1811 -2.7051 90)
			(unlocked yes)
			(layer "F.Fab")
			(hide yes)
			(effects
				(font
					(size 1.016 1.016)
					(thickness 0.1524)
				)
			)
		)
		(property "Device Type" "C402H22"
			(at 1.1811 -4.2291 90)
			(unlocked yes)
			(layer "F.Fab")
			(hide yes)
			(effects
				(font
					(size 1.016 1.016)
					(thickness 0.1524)
				)
			)
		)
		(duplicate_pad_numbers_are_jumpers no)
		(fp_rect
			(start -0.4318 0.9525)
			(end 0.4318 -0.9525)
			(stroke
				(width 0)
				(type default)
			)
			(fill no)
			(layer "F.CrtYd")
		)
		(fp_rect
			(start -0.4318 0.9525)
			(end 0.4318 -0.9525)
			(stroke
				(width 0)
				(type default)
			)
			(fill no)
			(layer "F.Fab")
		)
		(pad "1" smd custom
			(at 0 -0.4445 90)
			(size 0.1524 0.1524)
			(layers "F.Cu" "F.Mask" "F.Paste")
			(net "DP_RST_N")
			(options
				(clearance outline)
				(anchor circle)
			)
			(primitives
				(gr_poly
					(pts
						(arc
							(start 0.3048 -0.2032)
							(mid 0.275042 -0.275042)
							(end 0.2032 -0.3048)
						)
						(arc
							(start -0.2032 -0.3048)
							(mid -0.275042 -0.275042)
							(end -0.3048 -0.2032)
						)
						(arc
							(start -0.3048 0.2032)
							(mid -0.275042 0.275042)
							(end -0.2032 0.3048)
						)
						(arc
							(start 0.2032 0.3048)
							(mid 0.275042 0.275042)
							(end 0.3048 0.2032)
						)
					)
					(width 0)
					(fill yes)
				)
			)
		)
		(pad "2" smd custom
			(at 0 0.4445 90)
			(size 0.1524 0.1524)
			(layers "F.Cu" "F.Mask" "F.Paste")
			(net "GND")
			(options
				(clearance outline)
				(anchor circle)
			)
			(primitives
				(gr_poly
					(pts
						(arc
							(start 0.3048 -0.2032)
							(mid 0.275042 -0.275042)
							(end 0.2032 -0.3048)
						)
						(arc
							(start -0.2032 -0.3048)
							(mid -0.275042 -0.275042)
							(end -0.3048 -0.2032)
						)
						(arc
							(start -0.3048 0.2032)
							(mid -0.275042 0.275042)
							(end -0.2032 0.3048)
						)
						(arc
							(start 0.2032 0.3048)
							(mid 0.275042 0.275042)
							(end 0.3048 0.2032)
						)
					)
					(width 0)
					(fill yes)
				)
			)
		)
	)
	(footprint ""
		(layer "F.Cu")
		(at 164.973 -87.884)
		(property "Reference" "PTC7"
			(at 0 0 0)
			(layer "F.SilkS")
			(hide yes)
			(effects
				(font
					(size 1.27 1.27)
				)
			)
		)
		(property "Value" "SE470UF2VDM-GP"
			(at 0 -9.6012 0)
			(unlocked yes)
			(layer "F.Fab")
			(hide yes)
			(effects
				(font
					(size 1.016 1.016)
					(thickness 0.1524)
				)
			)
		)
		(property "Device Type" "CT7343H83"
			(at 0 -11.1252 0)
			(unlocked yes)
			(layer "F.Fab")
			(hide yes)
			(effects
				(font
					(size 1.016 1.016)
					(thickness 0.1524)
				)
			)
		)
		(duplicate_pad_numbers_are_jumpers no)
		(fp_line
			(start -2.286 -4.8768)
			(end -2.286 -2.032)
			(stroke
				(width 0.1524)
				(type default)
			)
			(layer "F.SilkS")
		)
		(fp_line
			(start -2.286 4.8768)
			(end -2.286 2.032)
			(stroke
				(width 0.1524)
				(type default)
			)
			(layer "F.SilkS")
		)
		(fp_line
			(start 2.1082 -4.699)
			(end -2.1082 -4.699)
			(stroke
				(width 0.508)
				(type default)
			)
			(layer "F.SilkS")
		)
		(fp_line
			(start 2.286 -4.8768)
			(end -2.286 -4.8768)
			(stroke
				(width 0.1524)
				(type default)
			)
			(layer "F.SilkS")
		)
		(fp_line
			(start 2.286 -2.032)
			(end 2.286 -4.8768)
			(stroke
				(width 0.1524)
				(type default)
			)
			(layer "F.SilkS")
		)
		(fp_line
			(start 2.286 2.032)
			(end 2.286 4.8768)
			(stroke
				(width 0.1524)
				(type default)
			)
			(layer "F.SilkS")
		)
		(fp_line
			(start 2.286 4.8768)
			(end -2.286 4.8768)
			(stroke
				(width 0.1524)
				(type default)
			)
			(layer "F.SilkS")
		)
		(fp_rect
			(start -2.1463 3.6449)
			(end 2.1463 -3.6449)
			(stroke
				(width 0)
				(type default)
			)
			(fill no)
			(layer "F.CrtYd")
		)
		(fp_poly
			(pts
				(xy -2.54 4.953) (xy -2.54 4.2926) (xy -3.81 4.2926) (xy -3.81 -4.2926) (xy -2.54 -4.2926) (xy -2.54 -4.953)
				(xy 2.54 -4.953) (xy 2.54 -4.2926) (xy 3.81 -4.2926) (xy 3.81 -1.6256) (xy 2.1463 -1.6256) (xy 2.1463 -3.6449)
				(xy -2.1463 -3.6449) (xy -2.1463 3.6449) (xy 2.1463 3.6449) (xy 2.1463 -1.6129) (xy 3.81 -1.6129)
				(xy 3.81 4.2926) (xy 2.54 4.2926) (xy 2.54 4.953)
			)
			(stroke
				(width 0)
				(type default)
			)
			(fill no)
			(layer "F.CrtYd")
		)
		(fp_rect
			(start -3.81 4.2926)
			(end -2.54 -4.2926)
			(stroke
				(width 0)
				(type default)
			)
			(fill no)
			(layer "F.Fab")
		)
		(fp_rect
			(start -2.54 4.953)
			(end 2.54 -4.953)
			(stroke
				(width 0)
				(type default)
			)
			(fill no)
			(layer "F.Fab")
		)
		(fp_rect
			(start 2.54 4.2926)
			(end 3.81 -4.2926)
			(stroke
				(width 0)
				(type default)
			)
			(fill no)
			(layer "F.Fab")
		)
		(pad "1" smd rect
			(at 0 -3.1496)
			(size 2.413 2.286)
			(layers "F.Cu" "F.Mask" "F.Paste")
			(net "P0V9_E")
		)
		(pad "2" smd rect
			(at 0 3.1496)
			(size 2.413 2.286)
			(layers "F.Cu" "F.Mask" "F.Paste")
			(net "GND")
		)
		(zone
			(layer "F.Cu")
			(hatch none 0.5)
			(connect_pads
				(clearance 0)
			)
			(min_thickness 0.25)
			(keepout
				(tracks allowed)
				(vias not_allowed)
				(pads allowed)
				(copperpour not_allowed)
				(footprints allowed)
			)
			(placement
				(enabled no)
				(sheetname "")
			)
			(fill
				(thermal_gap 0.5)
				(thermal_bridge_width 0.5)
				(island_removal_mode 0)
			)
			(polygon
				(pts
					(xy 163.4617 -83.2866) (xy 166.4843 -83.2866) (xy 166.4843 -86.1822) (xy 166.4843 -86.5124) (xy 163.4617 -86.5124)
					(xy 163.4617 -86.1822)
				)
			)
		)
		(zone
			(layer "F.Cu")
			(hatch none 0.5)
			(connect_pads
				(clearance 0)
			)
			(min_thickness 0.25)
			(keepout
				(tracks allowed)
				(vias not_allowed)
				(pads allowed)
				(copperpour not_allowed)
				(footprints allowed)
			)
			(placement
				(enabled no)
				(sheetname "")
			)
			(fill
				(thermal_gap 0.5)
				(thermal_bridge_width 0.5)
				(island_removal_mode 0)
			)
			(polygon
				(pts
					(xy 166.4843 -89.5731) (xy 166.4843 -92.4814) (xy 163.4617 -92.4814) (xy 163.4617 -89.5858) (xy 163.4617 -89.2556)
					(xy 166.4843 -89.2556)
				)
			)
		)
	)
	(footprint ""
		(layer "F.Cu")
		(at 199.39 -142.494 90)
		(property "Reference" "SR767"
			(at 0 0 90)
			(layer "F.SilkS")
			(hide yes)
			(effects
				(font
					(size 1.27 1.27)
				)
			)
		)
		(property "Value" "4K7R2F-GP"
			(at 0.064008 -3.993896 90)
			(unlocked yes)
			(layer "F.Fab")
			(hide yes)
			(effects
				(font
					(size 1.016 1.016)
					(thickness 0.1524)
				)
			)
		)
		(property "Device Type" "R402H16"
			(at 0.064008 -5.517896 90)
			(unlocked yes)
			(layer "F.Fab")
			(hide yes)
			(effects
				(font
					(size 1.016 1.016)
					(thickness 0.1524)
				)
			)
		)
		(duplicate_pad_numbers_are_jumpers no)
		(fp_line
			(start 0.508 -0.9398)
			(end -0.508 -0.9398)
			(stroke
				(width 0.1524)
				(type default)
			)
			(layer "F.SilkS")
		)
		(fp_line
			(start -0.508 -0.9398)
			(end -0.508 0.9398)
			(stroke
				(width 0.1524)
				(type default)
			)
			(layer "F.SilkS")
		)
		(fp_rect
			(start -0.508 0.9398)
			(end 0.508 -0.9398)
			(stroke
				(width 0)
				(type default)
			)
			(fill no)
			(layer "F.CrtYd")
		)
		(fp_rect
			(start -0.508 0.9398)
			(end 0.508 -0.9398)
			(stroke
				(width 0)
				(type default)
			)
			(fill no)
			(layer "F.Fab")
		)
		(pad "1" smd custom
			(at 0 -0.4445 90)
			(size 0.1397 0.1397)
			(layers "F.Cu" "F.Mask" "F.Paste")
			(net "EXP_EEPROM_A2")
			(options
				(clearance outline)
				(anchor circle)
			)
			(primitives
				(gr_poly
					(pts
						(arc
							(start -0.1778 -0.2794)
							(mid -0.249642 -0.249642)
							(end -0.2794 -0.1778)
						)
						(arc
							(start -0.2794 0.1778)
							(mid -0.249642 0.249642)
							(end -0.1778 0.2794)
						)
						(arc
							(start 0.1778 0.2794)
							(mid 0.249642 0.249642)
							(end 0.2794 0.1778)
						)
						(arc
							(start 0.2794 -0.1778)
							(mid 0.249642 -0.249642)
							(end 0.1778 -0.2794)
						)
					)
					(width 0)
					(fill yes)
				)
			)
		)
		(pad "2" smd custom
			(at 0 0.4445 90)
			(size 0.1397 0.1397)
			(layers "F.Cu" "F.Mask" "F.Paste")
			(net "GND")
			(options
				(clearance outline)
				(anchor circle)
			)
			(primitives
				(gr_poly
					(pts
						(arc
							(start -0.1778 -0.2794)
							(mid -0.249642 -0.249642)
							(end -0.2794 -0.1778)
						)
						(arc
							(start -0.2794 0.1778)
							(mid -0.249642 0.249642)
							(end -0.1778 0.2794)
						)
						(arc
							(start 0.1778 0.2794)
							(mid 0.249642 0.249642)
							(end 0.2794 0.1778)
						)
						(arc
							(start 0.2794 -0.1778)
							(mid 0.249642 -0.249642)
							(end 0.1778 -0.2794)
						)
					)
					(width 0)
					(fill yes)
				)
			)
		)
	)
	(footprint ""
		(layer "F.Cu")
		(at 333.375 -4.318 90)
		(property "Reference" "LED14"
			(at 0 0 90)
			(layer "F.SilkS")
			(hide yes)
			(effects
				(font
					(size 1.27 1.27)
				)
			)
		)
		(property "Value" "LED-Y-11-GP"
			(at -0.1016 -8.1788 90)
			(unlocked yes)
			(layer "F.Fab")
			(hide yes)
			(effects
				(font
					(size 1.016 1.016)
					(thickness 0.1524)
				)
			)
		)
		(property "Device Type" "19-21UBC-1"
			(at -0.0508 -9.8552 90)
			(unlocked yes)
			(layer "F.Fab")
			(hide yes)
			(effects
				(font
					(size 1.016 1.016)
					(thickness 0.1524)
				)
			)
		)
		(duplicate_pad_numbers_are_jumpers no)
		(fp_line
			(start 1.4351 -0.7747)
			(end 1.4351 0.7747)
			(stroke
				(width 0.1524)
				(type default)
			)
			(layer "F.SilkS")
		)
		(fp_line
			(start -1.4351 -0.7747)
			(end 1.4351 -0.7747)
			(stroke
				(width 0.1524)
				(type default)
			)
			(layer "F.SilkS")
		)
		(fp_line
			(start -1.7653 -0.7747)
			(end -1.7653 0.7747)
			(stroke
				(width 0.508)
				(type default)
			)
			(layer "F.SilkS")
		)
		(fp_line
			(start 1.4351 0.7747)
			(end -1.4351 0.7747)
			(stroke
				(width 0.1524)
				(type default)
			)
			(layer "F.SilkS")
		)
		(fp_line
			(start -1.4351 0.7747)
			(end -1.4351 -0.7747)
			(stroke
				(width 0.1524)
				(type default)
			)
			(layer "F.SilkS")
		)
		(fp_rect
			(start -2.0193 1.0287)
			(end 1.6891 -1.0287)
			(stroke
				(width 0)
				(type default)
			)
			(fill no)
			(layer "F.CrtYd")
		)
		(fp_poly
			(pts
				(xy -2.0193 -1.0287) (xy -2.0193 1.0287) (xy 1.6891 1.0287) (xy 1.6891 -1.0287)
			)
			(stroke
				(width 0)
				(type default)
			)
			(fill no)
			(layer "F.Fab")
		)
		(pad "1" smd rect
			(at -0.7112 0 90)
			(size 0.9398 1.0668)
			(layers "F.Cu" "F.Mask" "F.Paste")
			(net "DEBUG CONSOLE_LED_0")
		)
		(pad "2" smd rect
			(at 0.7112 0 90)
			(size 0.9398 1.0668)
			(layers "F.Cu" "F.Mask" "F.Paste")
			(net "CONSOLE_LED_0")
		)
	)
)
